(kicad_pcb
	(version 20260206)
	(generator "pcbnew")
	(generator_version "10.0")
	(general
		(thickness 1.6)
		(legacy_teardrops no)
	)
	(paper "A4")
	(title_block
		(title "03242023_DA0F0TMBIJ0_F0T_Motherboard_J_brd_V01_OCP.brd")
		(comment 1 "Grand Teton / footprints 4460-4465 of 6105")
	)
	(layers
		(0 "F.Cu" signal "TOP")
		(4 "In1.Cu" signal "GND")
		(6 "In2.Cu" signal "IN1")
		(8 "In3.Cu" signal "GND1")
		(10 "In4.Cu" signal "IN2")
		(12 "In5.Cu" signal "GND2")
		(14 "In6.Cu" signal "IN3")
		(16 "In7.Cu" signal "GND3")
		(18 "In8.Cu" signal "VCC")
		(20 "In9.Cu" signal "VCC1")
		(22 "In10.Cu" signal "GND4")
		(24 "In11.Cu" signal "IN4")
		(26 "In12.Cu" signal "GND5")
		(28 "In13.Cu" signal "IN5")
		(30 "In14.Cu" signal "GND6")
		(32 "In15.Cu" signal "IN6")
		(34 "In16.Cu" signal "GND7")
		(2 "B.Cu" signal "BOTTOM")
		(9 "F.Adhes" user "F.Adhesive")
		(11 "B.Adhes" user "B.Adhesive")
		(13 "F.Paste" user "Package Geometry/Pastemask Top")
		(15 "B.Paste" user "Package Geometry/Pastemask Bottom")
		(5 "F.SilkS" user "Ref Des/Silkscreen Top")
		(7 "B.SilkS" user "Ref Des/Silkscreen Bottom")
		(1 "F.Mask" user "Board Geometry/Soldermask Top")
		(3 "B.Mask" user "Board Geometry/Soldermask Bottom")
		(17 "Dwgs.User" user "User.Drawings")
		(19 "Cmts.User" user "User.Comments")
		(21 "Eco1.User" user "User.Eco1")
		(23 "Eco2.User" user "User.Eco2")
		(25 "Edge.Cuts" user "Board Geometry/Outline")
		(27 "Margin" user)
		(31 "F.CrtYd" user "Package Geometry/Place Bound Top")
		(29 "B.CrtYd" user "Package Geometry/Place Bound Bottom")
		(35 "F.Fab" user "Ref Des/Assembly Top")
		(33 "B.Fab" user "Ref Des/Assembly Bottom")
	)
	(footprint ""
		(layer "B.Cu")
		(at 368.158522 -261.953502 -90)
		(property "Reference" "C534"
			(at 0 0 90)
			(layer "B.SilkS")
			(hide yes)
			(effects
				(font
					(size 1.27 1.27)
				)
				(justify mirror)
			)
		)
		(property "Value" ""
			(at 0 0 90)
			(layer "B.Fab")
			(effects
				(font
					(size 1.27 1.27)
				)
				(justify mirror)
			)
		)
		(duplicate_pad_numbers_are_jumpers no)
		(fp_line
			(start -0.7874 0.4064)
			(end 0.7874 0.4064)
			(stroke
				(width 0.1524)
				(type default)
			)
			(layer "B.SilkS")
		)
		(fp_line
			(start 0.7874 0.4064)
			(end 0.7874 -0.4064)
			(stroke
				(width 0.1524)
				(type default)
			)
			(layer "B.SilkS")
		)
		(fp_line
			(start -0.7874 -0.4064)
			(end -0.7874 0.4064)
			(stroke
				(width 0.1524)
				(type default)
			)
			(layer "B.SilkS")
		)
		(fp_line
			(start 0.7874 -0.4064)
			(end -0.7874 -0.4064)
			(stroke
				(width 0.1524)
				(type default)
			)
			(layer "B.SilkS")
		)
		(fp_line
			(start -0.67945 0.3048)
			(end -0.120396 0.3048)
			(stroke
				(width 0.1)
				(type default)
			)
			(layer "B.Fab")
		)
		(fp_line
			(start -0.120396 0.3048)
			(end -0.120396 0.2794)
			(stroke
				(width 0.1)
				(type default)
			)
			(layer "B.Fab")
		)
		(fp_line
			(start 0.12065 0.3048)
			(end 0.67945 0.3048)
			(stroke
				(width 0.1)
				(type default)
			)
			(layer "B.Fab")
		)
		(fp_line
			(start 0.67945 0.3048)
			(end 0.67945 -0.305054)
			(stroke
				(width 0.1)
				(type default)
			)
			(layer "B.Fab")
		)
		(fp_line
			(start -0.120396 0.2794)
			(end 0.12065 0.2794)
			(stroke
				(width 0.1)
				(type default)
			)
			(layer "B.Fab")
		)
		(fp_line
			(start 0.12065 0.2794)
			(end 0.12065 0.3048)
			(stroke
				(width 0.1)
				(type default)
			)
			(layer "B.Fab")
		)
		(fp_line
			(start -0.12065 -0.2794)
			(end -0.12065 -0.3048)
			(stroke
				(width 0.1)
				(type default)
			)
			(layer "B.Fab")
		)
		(fp_line
			(start 0.12065 -0.2794)
			(end -0.12065 -0.2794)
			(stroke
				(width 0.1)
				(type default)
			)
			(layer "B.Fab")
		)
		(fp_line
			(start -0.67945 -0.3048)
			(end -0.67945 0.3048)
			(stroke
				(width 0.1)
				(type default)
			)
			(layer "B.Fab")
		)
		(fp_line
			(start -0.12065 -0.3048)
			(end -0.67945 -0.3048)
			(stroke
				(width 0.1)
				(type default)
			)
			(layer "B.Fab")
		)
		(fp_line
			(start 0.12065 -0.305054)
			(end 0.12065 -0.2794)
			(stroke
				(width 0.1)
				(type default)
			)
			(layer "B.Fab")
		)
		(fp_line
			(start 0.67945 -0.305054)
			(end 0.12065 -0.305054)
			(stroke
				(width 0.1)
				(type default)
			)
			(layer "B.Fab")
		)
		(pad "1" smd circle
			(at 0.40005 0 90)
			(size 0 0)
			(layers "B.Cu" "B.Mask" "B.Paste")
			(net "PVCCINFAON_CPU0")
		)
		(pad "2" smd circle
			(at -0.40005 0 90)
			(size 0 0)
			(layers "B.Cu" "B.Mask" "B.Paste")
			(net "GND")
		)
	)
	(footprint ""
		(layer "B.Cu")
		(at 354.221288 -359.47985 180)
		(property "Reference" "C3267"
			(at 0 0 0)
			(layer "B.SilkS")
			(hide yes)
			(effects
				(font
					(size 1.27 1.27)
				)
				(justify mirror)
			)
		)
		(property "Value" ""
			(at 0 0 0)
			(layer "B.Fab")
			(effects
				(font
					(size 1.27 1.27)
				)
				(justify mirror)
			)
		)
		(duplicate_pad_numbers_are_jumpers no)
		(fp_line
			(start 0.7874 0.4064)
			(end 0.7874 -0.4064)
			(stroke
				(width 0.1524)
				(type default)
			)
			(layer "B.SilkS")
		)
		(fp_line
			(start 0.7874 -0.4064)
			(end -0.7874 -0.4064)
			(stroke
				(width 0.1524)
				(type default)
			)
			(layer "B.SilkS")
		)
		(fp_line
			(start -0.7874 0.4064)
			(end 0.7874 0.4064)
			(stroke
				(width 0.1524)
				(type default)
			)
			(layer "B.SilkS")
		)
		(fp_line
			(start -0.7874 -0.4064)
			(end -0.7874 0.4064)
			(stroke
				(width 0.1524)
				(type default)
			)
			(layer "B.SilkS")
		)
		(fp_line
			(start 0.67945 0.3048)
			(end 0.67945 -0.305054)
			(stroke
				(width 0.1)
				(type default)
			)
			(layer "B.Fab")
		)
		(fp_line
			(start 0.67945 -0.305054)
			(end 0.12065 -0.305054)
			(stroke
				(width 0.1)
				(type default)
			)
			(layer "B.Fab")
		)
		(fp_line
			(start 0.12065 0.3048)
			(end 0.67945 0.3048)
			(stroke
				(width 0.1)
				(type default)
			)
			(layer "B.Fab")
		)
		(fp_line
			(start 0.12065 0.2794)
			(end 0.12065 0.3048)
			(stroke
				(width 0.1)
				(type default)
			)
			(layer "B.Fab")
		)
		(fp_line
			(start 0.12065 -0.2794)
			(end -0.12065 -0.2794)
			(stroke
				(width 0.1)
				(type default)
			)
			(layer "B.Fab")
		)
		(fp_line
			(start 0.12065 -0.305054)
			(end 0.12065 -0.2794)
			(stroke
				(width 0.1)
				(type default)
			)
			(layer "B.Fab")
		)
		(fp_line
			(start -0.120396 0.3048)
			(end -0.120396 0.2794)
			(stroke
				(width 0.1)
				(type default)
			)
			(layer "B.Fab")
		)
		(fp_line
			(start -0.120396 0.2794)
			(end 0.12065 0.2794)
			(stroke
				(width 0.1)
				(type default)
			)
			(layer "B.Fab")
		)
		(fp_line
			(start -0.12065 -0.2794)
			(end -0.12065 -0.3048)
			(stroke
				(width 0.1)
				(type default)
			)
			(layer "B.Fab")
		)
		(fp_line
			(start -0.12065 -0.3048)
			(end -0.67945 -0.3048)
			(stroke
				(width 0.1)
				(type default)
			)
			(layer "B.Fab")
		)
		(fp_line
			(start -0.67945 0.3048)
			(end -0.120396 0.3048)
			(stroke
				(width 0.1)
				(type default)
			)
			(layer "B.Fab")
		)
		(fp_line
			(start -0.67945 -0.3048)
			(end -0.67945 0.3048)
			(stroke
				(width 0.1)
				(type default)
			)
			(layer "B.Fab")
		)
		(pad "1" smd circle
			(at 0.40005 0)
			(size 0 0)
			(layers "B.Cu" "B.Mask" "B.Paste")
			(net "PVCCIN_CPU0_EN_R")
		)
		(pad "2" smd circle
			(at -0.40005 0)
			(size 0 0)
			(layers "B.Cu" "B.Mask" "B.Paste")
			(net "GND")
		)
	)
	(footprint ""
		(layer "B.Cu")
		(at 105.696258 -358.05491 -90)
		(property "Reference" "R309"
			(at 0 0 90)
			(layer "B.SilkS")
			(hide yes)
			(effects
				(font
					(size 1.27 1.27)
				)
				(justify mirror)
			)
		)
		(property "Value" ""
			(at 0 0 90)
			(layer "B.Fab")
			(effects
				(font
					(size 1.27 1.27)
				)
				(justify mirror)
			)
		)
		(duplicate_pad_numbers_are_jumpers no)
		(fp_line
			(start -0.7874 0.4064)
			(end 0.7874 0.4064)
			(stroke
				(width 0.1524)
				(type default)
			)
			(layer "B.SilkS")
		)
		(fp_line
			(start 0.7874 0.4064)
			(end 0.7874 -0.4064)
			(stroke
				(width 0.1524)
				(type default)
			)
			(layer "B.SilkS")
		)
		(fp_line
			(start -0.7874 -0.4064)
			(end -0.7874 0.4064)
			(stroke
				(width 0.1524)
				(type default)
			)
			(layer "B.SilkS")
		)
		(fp_line
			(start 0.7874 -0.4064)
			(end -0.7874 -0.4064)
			(stroke
				(width 0.1524)
				(type default)
			)
			(layer "B.SilkS")
		)
		(fp_line
			(start -0.67945 0.3048)
			(end -0.120396 0.3048)
			(stroke
				(width 0.1)
				(type default)
			)
			(layer "B.Fab")
		)
		(fp_line
			(start -0.120396 0.3048)
			(end -0.120396 0.2794)
			(stroke
				(width 0.1)
				(type default)
			)
			(layer "B.Fab")
		)
		(fp_line
			(start 0.12065 0.3048)
			(end 0.67945 0.3048)
			(stroke
				(width 0.1)
				(type default)
			)
			(layer "B.Fab")
		)
		(fp_line
			(start 0.67945 0.3048)
			(end 0.67945 -0.305054)
			(stroke
				(width 0.1)
				(type default)
			)
			(layer "B.Fab")
		)
		(fp_line
			(start -0.120396 0.2794)
			(end 0.12065 0.2794)
			(stroke
				(width 0.1)
				(type default)
			)
			(layer "B.Fab")
		)
		(fp_line
			(start 0.12065 0.2794)
			(end 0.12065 0.3048)
			(stroke
				(width 0.1)
				(type default)
			)
			(layer "B.Fab")
		)
		(fp_line
			(start -0.12065 -0.2794)
			(end -0.12065 -0.3048)
			(stroke
				(width 0.1)
				(type default)
			)
			(layer "B.Fab")
		)
		(fp_line
			(start 0.12065 -0.2794)
			(end -0.12065 -0.2794)
			(stroke
				(width 0.1)
				(type default)
			)
			(layer "B.Fab")
		)
		(fp_line
			(start -0.67945 -0.3048)
			(end -0.67945 0.3048)
			(stroke
				(width 0.1)
				(type default)
			)
			(layer "B.Fab")
		)
		(fp_line
			(start -0.12065 -0.3048)
			(end -0.67945 -0.3048)
			(stroke
				(width 0.1)
				(type default)
			)
			(layer "B.Fab")
		)
		(fp_line
			(start 0.12065 -0.305054)
			(end 0.12065 -0.2794)
			(stroke
				(width 0.1)
				(type default)
			)
			(layer "B.Fab")
		)
		(fp_line
			(start 0.67945 -0.305054)
			(end 0.12065 -0.305054)
			(stroke
				(width 0.1)
				(type default)
			)
			(layer "B.Fab")
		)
		(pad "1" smd circle
			(at 0.40005 0 90)
			(size 0 0)
			(layers "B.Cu" "B.Mask" "B.Paste")
			(net "FM_PVCCIN_CPU1_EN")
		)
		(pad "2" smd circle
			(at -0.40005 0 90)
			(size 0 0)
			(layers "B.Cu" "B.Mask" "B.Paste")
			(net "PVCCIN_CPU1_EN_R")
		)
	)
	(footprint ""
		(layer "B.Cu")
		(at 421.853614 -321.549776 -90)
		(property "Reference" "C36"
			(at 0 0 90)
			(layer "B.SilkS")
			(hide yes)
			(effects
				(font
					(size 1.27 1.27)
				)
				(justify mirror)
			)
		)
		(property "Value" ""
			(at 0 0 90)
			(layer "B.Fab")
			(effects
				(font
					(size 1.27 1.27)
				)
				(justify mirror)
			)
		)
		(duplicate_pad_numbers_are_jumpers no)
		(fp_line
			(start -1.524 0.762)
			(end 1.524 0.762)
			(stroke
				(width 0.1524)
				(type default)
			)
			(layer "B.SilkS")
		)
		(fp_line
			(start 1.524 0.762)
			(end 1.524 -0.762)
			(stroke
				(width 0.1524)
				(type default)
			)
			(layer "B.SilkS")
		)
		(fp_line
			(start -1.524 -0.762)
			(end -1.524 0.762)
			(stroke
				(width 0.1524)
				(type default)
			)
			(layer "B.SilkS")
		)
		(fp_line
			(start 1.524 -0.762)
			(end -1.524 -0.762)
			(stroke
				(width 0.1524)
				(type default)
			)
			(layer "B.SilkS")
		)
		(fp_line
			(start -1.1049 0.724916)
			(end -1.1049 -0.724916)
			(stroke
				(width 0.1)
				(type default)
			)
			(layer "B.Fab")
		)
		(fp_line
			(start 1.1049 0.724916)
			(end -1.1049 0.724916)
			(stroke
				(width 0.1)
				(type default)
			)
			(layer "B.Fab")
		)
		(fp_line
			(start -1.1049 -0.724916)
			(end 1.1049 -0.724916)
			(stroke
				(width 0.1)
				(type default)
			)
			(layer "B.Fab")
		)
		(fp_line
			(start 1.1049 -0.724916)
			(end 1.1049 0.724916)
			(stroke
				(width 0.1)
				(type default)
			)
			(layer "B.Fab")
		)
		(pad "1" smd rect
			(at 0.889 0 270)
			(size 1.016 1.27)
			(layers "B.Cu" "B.Mask" "B.Paste")
			(net "P12V_S3_AUX_CPU0_NVDIMM")
		)
		(pad "2" smd rect
			(at -0.889 0 270)
			(size 1.016 1.27)
			(layers "B.Cu" "B.Mask" "B.Paste")
			(net "GND")
		)
	)
	(footprint ""
		(layer "B.Cu")
		(at 62.996572 -151.23668)
		(property "Reference" "PC458_P1_2"
			(at 0 0 0)
			(layer "B.SilkS")
			(hide yes)
			(effects
				(font
					(size 1.27 1.27)
				)
				(justify mirror)
			)
		)
		(property "Value" ""
			(at 0 0 0)
			(layer "B.Fab")
			(effects
				(font
					(size 1.27 1.27)
				)
				(justify mirror)
			)
		)
		(duplicate_pad_numbers_are_jumpers no)
		(fp_line
			(start -1.524 -0.762)
			(end -1.524 0.762)
			(stroke
				(width 0.1524)
				(type default)
			)
			(layer "B.SilkS")
		)
		(fp_line
			(start -1.524 0.762)
			(end 1.524 0.762)
			(stroke
				(width 0.1524)
				(type default)
			)
			(layer "B.SilkS")
		)
		(fp_line
			(start 1.524 -0.762)
			(end -1.524 -0.762)
			(stroke
				(width 0.1524)
				(type default)
			)
			(layer "B.SilkS")
		)
		(fp_line
			(start 1.524 0.762)
			(end 1.524 -0.762)
			(stroke
				(width 0.1524)
				(type default)
			)
			(layer "B.SilkS")
		)
		(fp_line
			(start -1.1049 -0.724916)
			(end 1.1049 -0.724916)
			(stroke
				(width 0.1)
				(type default)
			)
			(layer "B.Fab")
		)
		(fp_line
			(start -1.1049 0.724916)
			(end -1.1049 -0.724916)
			(stroke
				(width 0.1)
				(type default)
			)
			(layer "B.Fab")
		)
		(fp_line
			(start 1.1049 -0.724916)
			(end 1.1049 0.724916)
			(stroke
				(width 0.1)
				(type default)
			)
			(layer "B.Fab")
		)
		(fp_line
			(start 1.1049 0.724916)
			(end -1.1049 0.724916)
			(stroke
				(width 0.1)
				(type default)
			)
			(layer "B.Fab")
		)
		(pad "1" smd rect
			(at 0.889 0)
			(size 1.016 1.27)
			(layers "B.Cu" "B.Mask" "B.Paste")
			(net "PVCCINFAON_CPU1")
		)
		(pad "2" smd rect
			(at -0.889 0)
			(size 1.016 1.27)
			(layers "B.Cu" "B.Mask" "B.Paste")
			(net "GND")
		)
	)
	(footprint ""
		(layer "B.Cu")
		(at 319.073022 -185.96991 -90)
		(property "Reference" "R195"
			(at 0 0 90)
			(layer "B.SilkS")
			(hide yes)
			(effects
				(font
					(size 1.27 1.27)
				)
				(justify mirror)
			)
		)
		(property "Value" ""
			(at 0 0 90)
			(layer "B.Fab")
			(effects
				(font
					(size 1.27 1.27)
				)
				(justify mirror)
			)
		)
		(duplicate_pad_numbers_are_jumpers no)
		(fp_line
			(start -0.7874 0.4064)
			(end 0.7874 0.4064)
			(stroke
				(width 0.1524)
				(type default)
			)
			(layer "B.SilkS")
		)
		(fp_line
			(start 0.7874 0.4064)
			(end 0.7874 -0.4064)
			(stroke
				(width 0.1524)
				(type default)
			)
			(layer "B.SilkS")
		)
		(fp_line
			(start -0.7874 -0.4064)
			(end -0.7874 0.4064)
			(stroke
				(width 0.1524)
				(type default)
			)
			(layer "B.SilkS")
		)
		(fp_line
			(start 0.7874 -0.4064)
			(end -0.7874 -0.4064)
			(stroke
				(width 0.1524)
				(type default)
			)
			(layer "B.SilkS")
		)
		(fp_line
			(start -0.67945 0.3048)
			(end -0.120396 0.3048)
			(stroke
				(width 0.1)
				(type default)
			)
			(layer "B.Fab")
		)
		(fp_line
			(start -0.120396 0.3048)
			(end -0.120396 0.2794)
			(stroke
				(width 0.1)
				(type default)
			)
			(layer "B.Fab")
		)
		(fp_line
			(start 0.12065 0.3048)
			(end 0.67945 0.3048)
			(stroke
				(width 0.1)
				(type default)
			)
			(layer "B.Fab")
		)
		(fp_line
			(start 0.67945 0.3048)
			(end 0.67945 -0.305054)
			(stroke
				(width 0.1)
				(type default)
			)
			(layer "B.Fab")
		)
		(fp_line
			(start -0.120396 0.2794)
			(end 0.12065 0.2794)
			(stroke
				(width 0.1)
				(type default)
			)
			(layer "B.Fab")
		)
		(fp_line
			(start 0.12065 0.2794)
			(end 0.12065 0.3048)
			(stroke
				(width 0.1)
				(type default)
			)
			(layer "B.Fab")
		)
		(fp_line
			(start -0.12065 -0.2794)
			(end -0.12065 -0.3048)
			(stroke
				(width 0.1)
				(type default)
			)
			(layer "B.Fab")
		)
		(fp_line
			(start 0.12065 -0.2794)
			(end -0.12065 -0.2794)
			(stroke
				(width 0.1)
				(type default)
			)
			(layer "B.Fab")
		)
		(fp_line
			(start -0.67945 -0.3048)
			(end -0.67945 0.3048)
			(stroke
				(width 0.1)
				(type default)
			)
			(layer "B.Fab")
		)
		(fp_line
			(start -0.12065 -0.3048)
			(end -0.67945 -0.3048)
			(stroke
				(width 0.1)
				(type default)
			)
			(layer "B.Fab")
		)
		(fp_line
			(start 0.12065 -0.305054)
			(end 0.12065 -0.2794)
			(stroke
				(width 0.1)
				(type default)
			)
			(layer "B.Fab")
		)
		(fp_line
			(start 0.67945 -0.305054)
			(end 0.12065 -0.305054)
			(stroke
				(width 0.1)
				(type default)
			)
			(layer "B.Fab")
		)
		(pad "1" smd circle
			(at 0.40005 0 90)
			(size 0 0)
			(layers "B.Cu" "B.Mask" "B.Paste")
			(net "H_CPU_NMI_LVC1_N")
		)
		(pad "2" smd circle
			(at -0.40005 0 90)
			(size 0 0)
			(layers "B.Cu" "B.Mask" "B.Paste")
			(net "H_CPU0_NMI_LVC1_N")
		)
	)
)
